(kicad_pcb
	(version 20260206)
	(generator "pcbnew")
	(generator_version "10.0")
	(general
		(thickness 1.6)
		(legacy_teardrops no)
	)
	(paper "A4")
	(title_block
		(title "01162023_DA0F0TEBIF0_F0T_Expander_BD_F_brd_V02_OCP.brd")
		(comment 1 "Grand Teton / footprints 1768-1774 of 9728")
	)
	(layers
		(0 "F.Cu" signal "TOP")
		(4 "In1.Cu" signal "GND")
		(6 "In2.Cu" signal "VCC")
		(8 "In3.Cu" signal "VCC1")
		(10 "In4.Cu" signal "GND1")
		(12 "In5.Cu" signal "IN1")
		(14 "In6.Cu" signal "GND2")
		(16 "In7.Cu" signal "IN2")
		(18 "In8.Cu" signal "GND3")
		(20 "In9.Cu" signal "IN3")
		(22 "In10.Cu" signal "GND4")
		(24 "In11.Cu" signal "IN4")
		(26 "In12.Cu" signal "GND5")
		(28 "In13.Cu" signal "IN5")
		(30 "In14.Cu" signal "GND6")
		(32 "In15.Cu" signal "IN6")
		(34 "In16.Cu" signal "GND7")
		(2 "B.Cu" signal "BOTTOM")
		(9 "F.Adhes" user "F.Adhesive")
		(11 "B.Adhes" user "B.Adhesive")
		(13 "F.Paste" user "Package Geometry/Pastemask Top")
		(15 "B.Paste" user "Package Geometry/Pastemask Bottom")
		(5 "F.SilkS" user "Ref Des/Silkscreen Top")
		(7 "B.SilkS" user "Ref Des/Silkscreen Bottom")
		(1 "F.Mask" user "Board Geometry/Soldermask Top")
		(3 "B.Mask" user "Board Geometry/Soldermask Bottom")
		(17 "Dwgs.User" user "User.Drawings")
		(19 "Cmts.User" user "User.Comments")
		(21 "Eco1.User" user "User.Eco1")
		(23 "Eco2.User" user "User.Eco2")
		(25 "Edge.Cuts" user "Board Geometry/Outline")
		(27 "Margin" user)
		(31 "F.CrtYd" user "Package Geometry/Place Bound Top")
		(29 "B.CrtYd" user "Package Geometry/Place Bound Bottom")
		(35 "F.Fab" user "Ref Des/Assembly Top")
		(33 "B.Fab" user "Ref Des/Assembly Bottom")
	)
	(footprint ""
		(layer "F.Cu")
		(at 330.374752 -48.753014 180)
		(property "Reference" "C327"
			(at 0 0 180)
			(layer "F.SilkS")
			(hide yes)
			(effects
				(font
					(size 1.27 1.27)
				)
			)
		)
		(property "Value" ""
			(at 0 0 180)
			(layer "F.Fab")
			(effects
				(font
					(size 1.27 1.27)
				)
			)
		)
		(duplicate_pad_numbers_are_jumpers no)
		(fp_line
			(start 0.7874 0.4064)
			(end -0.7874 0.4064)
			(stroke
				(width 0.1524)
				(type default)
			)
			(layer "F.SilkS")
		)
		(fp_line
			(start 0.7874 -0.4064)
			(end 0.7874 0.4064)
			(stroke
				(width 0.1524)
				(type default)
			)
			(layer "F.SilkS")
		)
		(fp_line
			(start -0.7874 0.4064)
			(end -0.7874 -0.4064)
			(stroke
				(width 0.1524)
				(type default)
			)
			(layer "F.SilkS")
		)
		(fp_line
			(start -0.7874 -0.4064)
			(end 0.7874 -0.4064)
			(stroke
				(width 0.1524)
				(type default)
			)
			(layer "F.SilkS")
		)
		(fp_line
			(start 0.67945 0.3048)
			(end 0.120396 0.3048)
			(stroke
				(width 0.1)
				(type default)
			)
			(layer "F.Fab")
		)
		(fp_line
			(start 0.67945 -0.3048)
			(end 0.67945 0.3048)
			(stroke
				(width 0.1)
				(type default)
			)
			(layer "F.Fab")
		)
		(fp_line
			(start 0.12065 -0.2794)
			(end 0.12065 -0.3048)
			(stroke
				(width 0.1)
				(type default)
			)
			(layer "F.Fab")
		)
		(fp_line
			(start 0.12065 -0.3048)
			(end 0.67945 -0.3048)
			(stroke
				(width 0.1)
				(type default)
			)
			(layer "F.Fab")
		)
		(fp_line
			(start 0.120396 0.3048)
			(end 0.120396 0.2794)
			(stroke
				(width 0.1)
				(type default)
			)
			(layer "F.Fab")
		)
		(fp_line
			(start 0.120396 0.2794)
			(end -0.12065 0.2794)
			(stroke
				(width 0.1)
				(type default)
			)
			(layer "F.Fab")
		)
		(fp_line
			(start -0.12065 0.3048)
			(end -0.67945 0.3048)
			(stroke
				(width 0.1)
				(type default)
			)
			(layer "F.Fab")
		)
		(fp_line
			(start -0.12065 0.2794)
			(end -0.12065 0.3048)
			(stroke
				(width 0.1)
				(type default)
			)
			(layer "F.Fab")
		)
		(fp_line
			(start -0.12065 -0.2794)
			(end 0.12065 -0.2794)
			(stroke
				(width 0.1)
				(type default)
			)
			(layer "F.Fab")
		)
		(fp_line
			(start -0.12065 -0.305054)
			(end -0.12065 -0.2794)
			(stroke
				(width 0.1)
				(type default)
			)
			(layer "F.Fab")
		)
		(fp_line
			(start -0.67945 0.3048)
			(end -0.67945 -0.305054)
			(stroke
				(width 0.1)
				(type default)
			)
			(layer "F.Fab")
		)
		(fp_line
			(start -0.67945 -0.305054)
			(end -0.12065 -0.305054)
			(stroke
				(width 0.1)
				(type default)
			)
			(layer "F.Fab")
		)
		(pad "1" smd circle
			(at -0.40005 0 180)
			(size 0 0)
			(layers "F.Cu" "F.Mask" "F.Paste")
			(net "P3V3_AUX")
		)
		(pad "2" smd circle
			(at 0.40005 0 180)
			(size 0 0)
			(layers "F.Cu" "F.Mask" "F.Paste")
			(net "GND")
		)
	)
	(footprint ""
		(layer "F.Cu")
		(at 448.328288 -405.070818 90)
		(property "Reference" "R5603"
			(at 0 0 90)
			(layer "F.SilkS")
			(hide yes)
			(effects
				(font
					(size 1.27 1.27)
				)
			)
		)
		(property "Value" ""
			(at 0 0 90)
			(layer "F.Fab")
			(effects
				(font
					(size 1.27 1.27)
				)
			)
		)
		(duplicate_pad_numbers_are_jumpers no)
		(fp_line
			(start 0.7874 -0.4064)
			(end 0.7874 0.4064)
			(stroke
				(width 0.1524)
				(type default)
			)
			(layer "F.SilkS")
		)
		(fp_line
			(start -0.7874 -0.4064)
			(end 0.7874 -0.4064)
			(stroke
				(width 0.1524)
				(type default)
			)
			(layer "F.SilkS")
		)
		(fp_line
			(start 0.7874 0.4064)
			(end -0.7874 0.4064)
			(stroke
				(width 0.1524)
				(type default)
			)
			(layer "F.SilkS")
		)
		(fp_line
			(start -0.7874 0.4064)
			(end -0.7874 -0.4064)
			(stroke
				(width 0.1524)
				(type default)
			)
			(layer "F.SilkS")
		)
		(fp_line
			(start -0.12065 -0.305054)
			(end -0.12065 -0.2794)
			(stroke
				(width 0.1)
				(type default)
			)
			(layer "F.Fab")
		)
		(fp_line
			(start -0.67945 -0.305054)
			(end -0.12065 -0.305054)
			(stroke
				(width 0.1)
				(type default)
			)
			(layer "F.Fab")
		)
		(fp_line
			(start 0.67945 -0.3048)
			(end 0.67945 0.3048)
			(stroke
				(width 0.1)
				(type default)
			)
			(layer "F.Fab")
		)
		(fp_line
			(start 0.12065 -0.3048)
			(end 0.67945 -0.3048)
			(stroke
				(width 0.1)
				(type default)
			)
			(layer "F.Fab")
		)
		(fp_line
			(start 0.12065 -0.2794)
			(end 0.12065 -0.3048)
			(stroke
				(width 0.1)
				(type default)
			)
			(layer "F.Fab")
		)
		(fp_line
			(start -0.12065 -0.2794)
			(end 0.12065 -0.2794)
			(stroke
				(width 0.1)
				(type default)
			)
			(layer "F.Fab")
		)
		(fp_line
			(start 0.120396 0.2794)
			(end -0.12065 0.2794)
			(stroke
				(width 0.1)
				(type default)
			)
			(layer "F.Fab")
		)
		(fp_line
			(start -0.12065 0.2794)
			(end -0.12065 0.3048)
			(stroke
				(width 0.1)
				(type default)
			)
			(layer "F.Fab")
		)
		(fp_line
			(start 0.67945 0.3048)
			(end 0.120396 0.3048)
			(stroke
				(width 0.1)
				(type default)
			)
			(layer "F.Fab")
		)
		(fp_line
			(start 0.120396 0.3048)
			(end 0.120396 0.2794)
			(stroke
				(width 0.1)
				(type default)
			)
			(layer "F.Fab")
		)
		(fp_line
			(start -0.12065 0.3048)
			(end -0.67945 0.3048)
			(stroke
				(width 0.1)
				(type default)
			)
			(layer "F.Fab")
		)
		(fp_line
			(start -0.67945 0.3048)
			(end -0.67945 -0.305054)
			(stroke
				(width 0.1)
				(type default)
			)
			(layer "F.Fab")
		)
		(pad "1" smd circle
			(at -0.40005 0 90)
			(size 0 0)
			(layers "F.Cu" "F.Mask" "F.Paste")
			(net "SMB_BIC_I2C6_MUX_THERMAL_R1_SCL")
		)
		(pad "2" smd circle
			(at 0.40005 0 90)
			(size 0 0)
			(layers "F.Cu" "F.Mask" "F.Paste")
			(net "SMB_LM75_1_SCL")
		)
	)
	(footprint ""
		(layer "F.Cu")
		(at 271.480534 -136.729724)
		(property "Reference" "C456"
			(at 0 0 0)
			(layer "F.SilkS")
			(hide yes)
			(effects
				(font
					(size 1.27 1.27)
				)
			)
		)
		(property "Value" ""
			(at 0 0 0)
			(layer "F.Fab")
			(effects
				(font
					(size 1.27 1.27)
				)
			)
		)
		(duplicate_pad_numbers_are_jumpers no)
		(fp_line
			(start -0.299974 -0.150114)
			(end 0.299974 -0.150114)
			(stroke
				(width 0.1)
				(type default)
			)
			(layer "F.Fab")
		)
		(fp_line
			(start -0.299974 0.150114)
			(end -0.299974 -0.150114)
			(stroke
				(width 0.1)
				(type default)
			)
			(layer "F.Fab")
		)
		(fp_line
			(start 0.299974 -0.150114)
			(end 0.299974 0.150114)
			(stroke
				(width 0.1)
				(type default)
			)
			(layer "F.Fab")
		)
		(fp_line
			(start 0.299974 0.150114)
			(end -0.299974 0.150114)
			(stroke
				(width 0.1)
				(type default)
			)
			(layer "F.Fab")
		)
		(pad "1" smd rect
			(at -0.2667 0)
			(size 0.3048 0.381)
			(layers "F.Cu" "F.Mask" "F.Paste")
			(net "P5E_PEX2_STN1_TX_DP<31>")
		)
		(pad "2" smd rect
			(at 0.2667 0)
			(size 0.3048 0.381)
			(layers "F.Cu" "F.Mask" "F.Paste")
			(net "P5E_PEX2_STN1_TX_C_DP<31>")
		)
	)
	(footprint ""
		(layer "F.Cu")
		(at 257.20929 -77.279754 -90)
		(property "Reference" "R1055"
			(at 0 0 270)
			(layer "F.SilkS")
			(hide yes)
			(effects
				(font
					(size 1.27 1.27)
				)
			)
		)
		(property "Value" ""
			(at 0 0 270)
			(layer "F.Fab")
			(effects
				(font
					(size 1.27 1.27)
				)
			)
		)
		(duplicate_pad_numbers_are_jumpers no)
		(fp_line
			(start -0.7874 0.4064)
			(end -0.7874 -0.4064)
			(stroke
				(width 0.1524)
				(type default)
			)
			(layer "F.SilkS")
		)
		(fp_line
			(start 0.7874 0.4064)
			(end -0.7874 0.4064)
			(stroke
				(width 0.1524)
				(type default)
			)
			(layer "F.SilkS")
		)
		(fp_line
			(start -0.7874 -0.4064)
			(end 0.7874 -0.4064)
			(stroke
				(width 0.1524)
				(type default)
			)
			(layer "F.SilkS")
		)
		(fp_line
			(start 0.7874 -0.4064)
			(end 0.7874 0.4064)
			(stroke
				(width 0.1524)
				(type default)
			)
			(layer "F.SilkS")
		)
		(fp_line
			(start -0.67945 0.3048)
			(end -0.67945 -0.305054)
			(stroke
				(width 0.1)
				(type default)
			)
			(layer "F.Fab")
		)
		(fp_line
			(start -0.12065 0.3048)
			(end -0.67945 0.3048)
			(stroke
				(width 0.1)
				(type default)
			)
			(layer "F.Fab")
		)
		(fp_line
			(start 0.120396 0.3048)
			(end 0.120396 0.2794)
			(stroke
				(width 0.1)
				(type default)
			)
			(layer "F.Fab")
		)
		(fp_line
			(start 0.67945 0.3048)
			(end 0.120396 0.3048)
			(stroke
				(width 0.1)
				(type default)
			)
			(layer "F.Fab")
		)
		(fp_line
			(start -0.12065 0.2794)
			(end -0.12065 0.3048)
			(stroke
				(width 0.1)
				(type default)
			)
			(layer "F.Fab")
		)
		(fp_line
			(start 0.120396 0.2794)
			(end -0.12065 0.2794)
			(stroke
				(width 0.1)
				(type default)
			)
			(layer "F.Fab")
		)
		(fp_line
			(start -0.12065 -0.2794)
			(end 0.12065 -0.2794)
			(stroke
				(width 0.1)
				(type default)
			)
			(layer "F.Fab")
		)
		(fp_line
			(start 0.12065 -0.2794)
			(end 0.12065 -0.3048)
			(stroke
				(width 0.1)
				(type default)
			)
			(layer "F.Fab")
		)
		(fp_line
			(start 0.12065 -0.3048)
			(end 0.67945 -0.3048)
			(stroke
				(width 0.1)
				(type default)
			)
			(layer "F.Fab")
		)
		(fp_line
			(start 0.67945 -0.3048)
			(end 0.67945 0.3048)
			(stroke
				(width 0.1)
				(type default)
			)
			(layer "F.Fab")
		)
		(fp_line
			(start -0.67945 -0.305054)
			(end -0.12065 -0.305054)
			(stroke
				(width 0.1)
				(type default)
			)
			(layer "F.Fab")
		)
		(fp_line
			(start -0.12065 -0.305054)
			(end -0.12065 -0.2794)
			(stroke
				(width 0.1)
				(type default)
			)
			(layer "F.Fab")
		)
		(pad "1" smd circle
			(at -0.40005 0 270)
			(size 0 0)
			(layers "F.Cu" "F.Mask" "F.Paste")
			(net "FM_CLK_EN_R")
		)
		(pad "2" smd circle
			(at 0.40005 0 270)
			(size 0 0)
			(layers "F.Cu" "F.Mask" "F.Paste")
			(net "P3V3")
		)
	)
	(footprint ""
		(layer "F.Cu")
		(at 352.920554 -86.073234)
		(property "Reference" "R1621"
			(at 0 0 0)
			(layer "F.SilkS")
			(hide yes)
			(effects
				(font
					(size 1.27 1.27)
				)
			)
		)
		(property "Value" ""
			(at 0 0 0)
			(layer "F.Fab")
			(effects
				(font
					(size 1.27 1.27)
				)
			)
		)
		(duplicate_pad_numbers_are_jumpers no)
		(fp_line
			(start -0.7874 -0.4064)
			(end 0.7874 -0.4064)
			(stroke
				(width 0.1524)
				(type default)
			)
			(layer "F.SilkS")
		)
		(fp_line
			(start -0.7874 0.4064)
			(end -0.7874 -0.4064)
			(stroke
				(width 0.1524)
				(type default)
			)
			(layer "F.SilkS")
		)
		(fp_line
			(start 0.7874 -0.4064)
			(end 0.7874 0.4064)
			(stroke
				(width 0.1524)
				(type default)
			)
			(layer "F.SilkS")
		)
		(fp_line
			(start 0.7874 0.4064)
			(end -0.7874 0.4064)
			(stroke
				(width 0.1524)
				(type default)
			)
			(layer "F.SilkS")
		)
		(fp_line
			(start -0.67945 -0.305054)
			(end -0.12065 -0.305054)
			(stroke
				(width 0.1)
				(type default)
			)
			(layer "F.Fab")
		)
		(fp_line
			(start -0.67945 0.3048)
			(end -0.67945 -0.305054)
			(stroke
				(width 0.1)
				(type default)
			)
			(layer "F.Fab")
		)
		(fp_line
			(start -0.12065 -0.305054)
			(end -0.12065 -0.2794)
			(stroke
				(width 0.1)
				(type default)
			)
			(layer "F.Fab")
		)
		(fp_line
			(start -0.12065 -0.2794)
			(end 0.12065 -0.2794)
			(stroke
				(width 0.1)
				(type default)
			)
			(layer "F.Fab")
		)
		(fp_line
			(start -0.12065 0.2794)
			(end -0.12065 0.3048)
			(stroke
				(width 0.1)
				(type default)
			)
			(layer "F.Fab")
		)
		(fp_line
			(start -0.12065 0.3048)
			(end -0.67945 0.3048)
			(stroke
				(width 0.1)
				(type default)
			)
			(layer "F.Fab")
		)
		(fp_line
			(start 0.120396 0.2794)
			(end -0.12065 0.2794)
			(stroke
				(width 0.1)
				(type default)
			)
			(layer "F.Fab")
		)
		(fp_line
			(start 0.120396 0.3048)
			(end 0.120396 0.2794)
			(stroke
				(width 0.1)
				(type default)
			)
			(layer "F.Fab")
		)
		(fp_line
			(start 0.12065 -0.3048)
			(end 0.67945 -0.3048)
			(stroke
				(width 0.1)
				(type default)
			)
			(layer "F.Fab")
		)
		(fp_line
			(start 0.12065 -0.2794)
			(end 0.12065 -0.3048)
			(stroke
				(width 0.1)
				(type default)
			)
			(layer "F.Fab")
		)
		(fp_line
			(start 0.67945 -0.3048)
			(end 0.67945 0.3048)
			(stroke
				(width 0.1)
				(type default)
			)
			(layer "F.Fab")
		)
		(fp_line
			(start 0.67945 0.3048)
			(end 0.120396 0.3048)
			(stroke
				(width 0.1)
				(type default)
			)
			(layer "F.Fab")
		)
		(pad "1" smd circle
			(at -0.40005 0)
			(size 0 0)
			(layers "F.Cu" "F.Mask" "F.Paste")
			(net "SMB_BIC_I2C9_MUX1_SSD9_R_SCL")
		)
		(pad "2" smd circle
			(at 0.40005 0)
			(size 0 0)
			(layers "F.Cu" "F.Mask" "F.Paste")
			(net "SMB_BIC_I2C9_MUX1_SSD9_SCL")
		)
	)
	(footprint ""
		(layer "F.Cu")
		(at 193.250312 -350.098614 90)
		(property "Reference" "C2540"
			(at 0 0 90)
			(layer "F.SilkS")
			(hide yes)
			(effects
				(font
					(size 1.27 1.27)
				)
			)
		)
		(property "Value" ""
			(at 0 0 90)
			(layer "F.Fab")
			(effects
				(font
					(size 1.27 1.27)
				)
			)
		)
		(duplicate_pad_numbers_are_jumpers no)
		(fp_line
			(start 0.299974 -0.150114)
			(end 0.299974 0.150114)
			(stroke
				(width 0.1)
				(type default)
			)
			(layer "F.Fab")
		)
		(fp_line
			(start -0.299974 -0.150114)
			(end 0.299974 -0.150114)
			(stroke
				(width 0.1)
				(type default)
			)
			(layer "F.Fab")
		)
		(fp_line
			(start 0.299974 0.150114)
			(end -0.299974 0.150114)
			(stroke
				(width 0.1)
				(type default)
			)
			(layer "F.Fab")
		)
		(fp_line
			(start -0.299974 0.150114)
			(end -0.299974 -0.150114)
			(stroke
				(width 0.1)
				(type default)
			)
			(layer "F.Fab")
		)
		(pad "1" smd rect
			(at -0.2667 0 90)
			(size 0.3048 0.381)
			(layers "F.Cu" "F.Mask" "F.Paste")
			(net "P5E_PEX1_STN4_TX_DP<65>")
		)
		(pad "2" smd rect
			(at 0.2667 0 90)
			(size 0.3048 0.381)
			(layers "F.Cu" "F.Mask" "F.Paste")
			(net "P5E_PEX1_STN4_TX_C_DP<65>")
		)
	)
	(footprint ""
		(layer "F.Cu")
		(at 15.142718 -70.844918 -90)
		(property "Reference" "PD86"
			(at 2.112518 2.187448 90)
			(unlocked yes)
			(layer "F.SilkS")
			(effects
				(font
					(size 0.7874 0.5842)
					(thickness 0.1524)
				)
				(justify left)
			)
		)
		(property "Value" ""
			(at 0 0 270)
			(layer "F.Fab")
			(effects
				(font
					(size 1.27 1.27)
				)
			)
		)
		(duplicate_pad_numbers_are_jumpers no)
		(fp_line
			(start -3.400044 1.459992)
			(end -3.400044 -1.459992)
			(stroke
				(width 0.1524)
				(type default)
			)
			(layer "F.SilkS")
		)
		(fp_line
			(start 4.107942 1.459992)
			(end -3.400044 1.459992)
			(stroke
				(width 0.1524)
				(type default)
			)
			(layer "F.SilkS")
		)
		(fp_line
			(start -3.400044 -1.459992)
			(end 4.107942 -1.459992)
			(stroke
				(width 0.1524)
				(type default)
			)
			(layer "F.SilkS")
		)
		(fp_line
			(start 4.107942 -1.459992)
			(end 4.107942 1.459992)
			(stroke
				(width 0.1524)
				(type default)
			)
			(layer "F.SilkS")
		)
		(fp_poly
			(pts
				(xy 4.107942 -1.459992) (xy 4.107942 1.459992) (xy 3.308096 1.459992) (xy 3.308096 -1.459992)
			)
			(stroke
				(width 0)
				(type default)
			)
			(fill yes)
			(layer "F.SilkS")
		)
		(fp_line
			(start -2.29997 1.459992)
			(end -2.29997 -1.459992)
			(stroke
				(width 0.1)
				(type default)
			)
			(layer "F.Fab")
		)
		(fp_line
			(start 2.29997 1.459992)
			(end -2.29997 1.459992)
			(stroke
				(width 0.1)
				(type default)
			)
			(layer "F.Fab")
		)
		(fp_line
			(start -2.29997 -1.459992)
			(end 2.29997 -1.459992)
			(stroke
				(width 0.1)
				(type default)
			)
			(layer "F.Fab")
		)
		(fp_line
			(start 2.29997 -1.459992)
			(end 2.29997 1.459992)
			(stroke
				(width 0.1)
				(type default)
			)
			(layer "F.Fab")
		)
		(fp_text user "-"
			(at 5.4102 0.29845 90)
			(unlocked yes)
			(layer "F.SilkS")
			(effects
				(font
					(size 1.905 1.4224)
					(thickness 0.1524)
				)
				(justify left)
			)
		)
		(fp_text user "+"
			(at -4.729734 -1.377442 270)
			(unlocked yes)
			(layer "F.SilkS")
			(effects
				(font
					(size 1.905 1.4224)
					(thickness 0.1524)
				)
				(justify left)
			)
		)
		(fp_text user "-"
			(at 5.4102 0.29845 90)
			(unlocked yes)
			(layer "F.Fab")
			(effects
				(font
					(size 1.905 1.4224)
					(thickness 0.1524)
				)
				(justify left)
			)
		)
		(fp_text user "+"
			(at -4.7752 -0.12065 270)
			(unlocked yes)
			(layer "F.Fab")
			(effects
				(font
					(size 1.905 1.4224)
					(thickness 0.1524)
				)
				(justify left)
			)
		)
		(pad "A" smd rect
			(at -1.999996 0)
			(size 1.7018 2.5146)
			(layers "F.Cu" "F.Mask" "F.Paste")
			(net "GND")
		)
		(pad "C" smd rect
			(at 1.999996 0)
			(size 1.7018 2.5146)
			(layers "F.Cu" "F.Mask" "F.Paste")
			(net "P12V_SSD0_R")
		)
	)
)
